# BASEBOARD_FAB2 (Tioga Pass) — schematic netlist excerpt (pin names and nets, part order shuffled) for the footprints in the layout excerpt that follows; sources: Cadence DE-HDL packaged netlist, KiCad conversion of Wiwynn_Tioga_Pass_MB.brd

J4A1  SCONN288_H44441004  SCONN  pkg PIP  page 53
  \12v\(1)  = P12V_NVDIMM_DEF
  VSS(93)  = GND
  DQ(4)  = M_F_DQ<5>
  VSS(92)  = GND
  DQ(0)  = M_F_DQ<1>
  VSS(91)  = GND
  DQS9P  = M_F_DQS_DP<9>
  DQS9N  = M_F_DQS_DN<9>
  VSS(90)  = GND
  DQ(6)  = M_F_DQ<7>
  VSS(89)  = GND
  DQ(2)  = M_F_DQ<3>
  VSS(88)  = GND
  DQ(12)  = M_F_DQ<13>
  VSS(87)  = GND
  DQ(8)  = M_F_DQ<9>
  VSS(86)  = GND
  DQS10P  = M_F_DQS_DP<10>
  DQS10N  = M_F_DQS_DN<10>
  VSS(85)  = GND
  DQ(14)  = M_F_DQ<15>
  VSS(84)  = GND
  DQ(10)  = M_F_DQ<11>
  VSS(83)  = GND
  DQ(20)  = M_F_DQ<21>
  VSS(82)  = GND
  DQ(16)  = M_F_DQ<17>
  VSS(81)  = GND
  DQS11P  = M_F_DQS_DP<11>
  DQS11N  = M_F_DQS_DN<11>
  VSS(80)  = GND
  DQ(22)  = M_F_DQ<23>
  VSS(79)  = GND
  DQ(18)  = M_F_DQ<19>
  VSS(78)  = GND
  DQ(28)  = M_F_DQ<29>
  VSS(77)  = GND
  DQ(24)  = M_F_DQ<25>
  VSS(76)  = GND
  DQS12P  = M_F_DQS_DP<12>
  DQS12N  = M_F_DQS_DN<12>
  VSS(75)  = GND
  DQ(30)  = M_F_DQ<31>
  VSS(74)  = GND
  DQ(26)  = M_F_DQ<27>
  VSS(73)  = GND
  CB(4)  = M_F_ECC<5>
  VSS(72)  = GND
  CB(0)  = M_F_ECC<1>
  VSS(71)  = GND
  DQS17P  = M_F_DQS_DP<17>
  DQS17N  = M_F_DQS_DN<17>
  VSS(70)  = GND
  CB(6)  = M_F_ECC<7>
  VSS(69)  = GND
  CB(2)  = M_F_ECC<3>
  VSS(68)  = GND
  RESET_N  = M_DEF_RST_N
  VDD(25)  = PVDDQ_DEF
  CKE(0)  = M_F_CKE<0>
  VDD(24)  = PVDDQ_DEF
  ACT_N  = M_F_ACT_N
  BG(0)  = M_F_BG<0>
  VDD(23)  = PVDDQ_DEF
  A12  = M_F_MA<12>
  A9  = M_F_MA<9>
  VDD(22)  = PVDDQ_DEF
  A8  = M_F_MA<8>
  A6  = M_F_MA<6>
  VDD(21)  = PVDDQ_DEF
  A3  = M_F_MA<3>
  A1  = M_F_MA<1>
  VDD(20)  = PVDDQ_DEF
  CK0P  = M_F_CLK_DP<0>
  CK0N  = M_F_CLK_DN<0>
  VDD(19)  = PVDDQ_DEF
  VTT(1)  = PVTT_DEF
  EVENT_N  = FM_DIMM_EVENT_COD_N
  A0  = M_F_MA<0>
  VDD(18)  = PVDDQ_DEF
  BA(0)  = M_F_BA<0>
  A16_RAS_N  = M_F_MA<16>
  VDD(17)  = PVDDQ_DEF
  S0_N  = M_F_CS_N<0>
  VDD(16)  = PVDDQ_DEF
  A15_CAS_N  = M_F_MA<15>
  ODT(0)  = M_F_ODT<0>
  VDD(15)  = PVDDQ_DEF
  S1_N  = M_F_CS_N<1>
  VDD(14)  = PVDDQ_DEF
  ODT(1)  = M_F_ODT<1>
  VDD(13)  = PVDDQ_DEF
  S2_N_C(0)  = M_F_CS_N<2>
  VSS(67)  = GND
  DQ(36)  = M_F_DQ<37>
  VSS(66)  = GND
  DQ(32)  = M_F_DQ<33>
  VSS(65)  = GND
  DQS13P  = M_F_DQS_DP<13>
  DQS13N  = M_F_DQS_DN<13>
  VSS(64)  = GND
  DQ(38)  = M_F_DQ<39>
  VSS(63)  = GND
  DQ(34)  = M_F_DQ<35>
  VSS(62)  = GND
  DQ(44)  = M_F_DQ<45>
  VSS(61)  = GND
  DQ(40)  = M_F_DQ<41>
  VSS(60)  = GND
  DQS14P  = M_F_DQS_DP<14>
  DQS14N  = M_F_DQS_DN<14>
  VSS(59)  = GND
  DQ(46)  = M_F_DQ<47>
  VSS(58)  = GND
  DQ(42)  = M_F_DQ<43>
  VSS(57)  = GND
  DQ(52)  = M_F_DQ<53>
  VSS(56)  = GND
  DQ(48)  = M_F_DQ<49>
  VSS(55)  = GND
  DQS15P  = M_F_DQS_DP<15>
  DQS15N  = M_F_DQS_DN<15>
  VSS(54)  = GND
  DQ(54)  = M_F_DQ<55>
  VSS(53)  = GND
  DQ(50)  = M_F_DQ<51>
  VSS(52)  = GND
  DQ(60)  = M_F_DQ<61>
  VSS(51)  = GND
  DQ(56)  = M_F_DQ<57>
  VSS(50)  = GND
  DQS16P  = M_F_DQS_DP<16>
  DQS16N  = M_F_DQS_DN<16>
  VSS(49)  = GND
  DQ(62)  = M_F_DQ<63>
  VSS(48)  = GND
  DQ(58)  = M_F_DQ<59>
  VSS(47)  = GND
  SA(0)  = GND
  SA(1)  = GND
  SCL  = SMB_DDR_DEF_VPP_SCL
  VPP(4)  = PVPP_DEF
  VPP(3)  = PVPP_DEF
  RFU(2)  = TP_CH_F_DIMM_F0_RFU_2
  \12v\(0)  = P12V_NVDIMM_DEF
  VREFCA  = M_F_VREF
  VSS(46)  = GND
  DQ(5)  = M_F_DQ<4>
  VSS(45)  = GND
  DQ(1)  = M_F_DQ<0>
  VSS(44)  = GND
  DQS0N  = M_F_DQS_DN<0>
  DQS0P  = M_F_DQS_DP<0>
  VSS(43)  = GND
  DQ(7)  = M_F_DQ<6>
  VSS(42)  = GND
  DQ(3)  = M_F_DQ<2>
  VSS(41)  = GND
  DQ(13)  = M_F_DQ<12>
  VSS(40)  = GND
  DQ(9)  = M_F_DQ<8>
  VSS(39)  = GND
  DQS1N  = M_F_DQS_DN<1>
  DQS1P  = M_F_DQS_DP<1>
  VSS(38)  = GND
  DQ(15)  = M_F_DQ<14>
  VSS(37)  = GND
  DQ(11)  = M_F_DQ<10>
  VSS(36)  = GND
  DQ(21)  = M_F_DQ<20>
  VSS(35)  = GND
  DQ(17)  = M_F_DQ<16>
  VSS(34)  = GND
  DQS2N  = M_F_DQS_DN<2>
  DQS2P  = M_F_DQS_DP<2>
  VSS(33)  = GND
  DQ(23)  = M_F_DQ<22>
  VSS(32)  = GND
  DQ(19)  = M_F_DQ<18>
  VSS(31)  = GND
  DQ(29)  = M_F_DQ<28>
  VSS(30)  = GND
  DQ(25)  = M_F_DQ<24>
  VSS(29)  = GND
  DQS3N  = M_F_DQS_DN<3>
  DQS3P  = M_F_DQS_DP<3>
  VSS(28)  = GND
  DQ(31)  = M_F_DQ<30>
  VSS(27)  = GND
  DQ(27)  = M_F_DQ<26>
  VSS(26)  = GND
  CB(5)  = M_F_ECC<4>
  VSS(25)  = GND
  CB(1)  = M_F_ECC<0>
  VSS(24)  = GND
  DQS8N  = M_F_DQS_DN<8>
  DQS8P  = M_F_DQS_DP<8>
  VSS(23)  = GND
  CB(7)  = M_F_ECC<6>
  VSS(22)  = GND
  CB(3)  = M_F_ECC<2>
  VSS(21)  = GND
  CKE(1)  = M_F_CKE<1>
  VDD(12)  = PVDDQ_DEF
  RFU(0)  = TP_CH_F_DIMM_F0_RFU_0
  VDD(11)  = PVDDQ_DEF
  BG(1)  = M_F_BG<1>
  ALERT_N  = M_F_ALERT_N
  VDD(10)  = PVDDQ_DEF
  A11  = M_F_MA<11>
  A7  = M_F_MA<7>
  VDD(9)  = PVDDQ_DEF
  A5  = M_F_MA<5>
  A4  = M_F_MA<4>
  VDD(8)  = PVDDQ_DEF
  A2  = M_F_MA<2>
  VDD(7)  = PVDDQ_DEF
  CK1P  = M_F_CLK_DP<1>
  CK1N  = M_F_CLK_DN<1>
  VDD(6)  = PVDDQ_DEF
  VTT(0)  = PVTT_DEF
  PAR  = M_F_PAR
  VDD(5)  = PVDDQ_DEF
  BA(1)  = M_F_BA<1>
  A10  = M_F_MA<10>
  VDD(4)  = PVDDQ_DEF
  RFU(1)  = TP_CH_F_DIMM_F0_RFU_1
  A14_WE_N  = M_F_MA<14>
  VDD(3)  = PVDDQ_DEF
  SAVE_N_NC  = FM_ADR_COMPLETE_DEF_N
  VDD(2)  = PVDDQ_DEF
  A13  = M_F_MA<13>
  VDD(1)  = PVDDQ_DEF
  A17  = M_F_MA<17>
  C(2)  = M_F_C<2>
  VDD(0)  = PVDDQ_DEF
  S3_N_C(1)  = M_F_CS_N<3>
  SA(2)  = PVPP_DEF
  VSS(20)  = GND
  DQ(37)  = M_F_DQ<36>
  VSS(19)  = GND
  DQ(33)  = M_F_DQ<32>
  VSS(18)  = GND
  DQS4N  = M_F_DQS_DN<4>
  DQS4P  = M_F_DQS_DP<4>
  VSS(17)  = GND
  DQ(39)  = M_F_DQ<38>
  VSS(16)  = GND
  DQ(35)  = M_F_DQ<34>
  VSS(15)  = GND
  DQ(45)  = M_F_DQ<44>
  VSS(14)  = GND
  DQ(41)  = M_F_DQ<40>
  VSS(13)  = GND
  DQS5N  = M_F_DQS_DN<5>
  DQS5P  = M_F_DQS_DP<5>
  VSS(12)  = GND
  DQ(47)  = M_F_DQ<46>
  VSS(11)  = GND
  DQ(43)  = M_F_DQ<42>
  VSS(10)  = GND
  DQ(53)  = M_F_DQ<52>
  VSS(9)  = GND
  DQ(49)  = M_F_DQ<48>
  VSS(8)  = GND
  DQS6N  = M_F_DQS_DN<6>
  DQS6P  = M_F_DQS_DP<6>
  VSS(7)  = GND
  DQ(55)  = M_F_DQ<54>
  VSS(6)  = GND
  DQ(51)  = M_F_DQ<50>
  VSS(5)  = GND
  DQ(61)  = M_F_DQ<60>
  VSS(4)  = GND
  DQ(57)  = M_F_DQ<56>
  VSS(3)  = GND
  DQS7N  = M_F_DQS_DN<7>
  DQS7P  = M_F_DQS_DP<7>
  VSS(2)  = GND
  DQ(63)  = M_F_DQ<62>
  VSS(1)  = GND
  DQ(59)  = M_F_DQ<58>
  VSS(0)  = GND
  VDDSPD  = PVPP_DEF
  SDA  = SMB_DDR_DEF_VPP_SDA
  VPP(1)  = PVPP_DEF
  VPP(0)  = PVPP_DEF
  VPP(2)  = PVPP_DEF

(kicad_pcb
	(version 20260206)
	(generator "pcbnew")
	(generator_version "10.0")
	(general
		(thickness 1.6)
		(legacy_teardrops no)
	)
	(paper "A4")
	(title_block
		(title "Wiwynn_Tioga_Pass_MB.brd")
		(comment 1 "Tioga Pass / footprint 431 of 4770 (J4A1), pads 1-51 of 291")
	)
	(layers
		(0 "F.Cu" signal "TOP")
		(4 "In1.Cu" signal "L2GND")
		(6 "In2.Cu" signal "L3")
		(8 "In3.Cu" signal "L4GND")
		(10 "In4.Cu" signal "L5")
		(12 "In5.Cu" signal "L6GND")
		(14 "In6.Cu" signal "L7VCC")
		(16 "In7.Cu" signal "L8VCC")
		(18 "In8.Cu" signal "L9GND")
		(20 "In9.Cu" signal "L10")
		(22 "In10.Cu" signal "L11GND")
		(24 "In11.Cu" signal "L12")
		(26 "In12.Cu" signal "L13GND")
		(2 "B.Cu" signal "BOTTOM")
		(9 "F.Adhes" user "F.Adhesive")
		(11 "B.Adhes" user "B.Adhesive")
		(13 "F.Paste" user "Package Geometry/Pastemask Top")
		(15 "B.Paste" user "Package Geometry/Pastemask Bottom")
		(5 "F.SilkS" user "Ref Des/Silkscreen Top")
		(7 "B.SilkS" user "Ref Des/Silkscreen Bottom")
		(1 "F.Mask" user "Board Geometry/Soldermask Top")
		(3 "B.Mask" user "Board Geometry/Soldermask Bottom")
		(17 "Dwgs.User" user "User.Drawings")
		(19 "Cmts.User" user "User.Comments")
		(21 "Eco1.User" user "User.Eco1")
		(23 "Eco2.User" user "User.Eco2")
		(25 "Edge.Cuts" user "Board Geometry/Outline")
		(27 "Margin" user)
		(31 "F.CrtYd" user "Package Geometry/Place Bound Top")
		(29 "B.CrtYd" user "Package Geometry/Place Bound Bottom")
		(35 "F.Fab" user "Ref Des/Assembly Top")
		(33 "B.Fab" user "Ref Des/Assembly Bottom")
	)
	(footprint ""
		(layer "F.Cu")
		(at 194.700398 -152.273 90)
		(property "Reference" "J4A1"
			(at -2.699512 42.53611 0)
			(unlocked yes)
			(layer "F.SilkS")
			(effects
				(font
					(size 0.7874 0.5842)
					(thickness 0.1524)
				)
				(justify left)
			)
		)
		(property "Value" ""
			(at 0 0 90)
			(layer "F.Fab")
			(effects
				(font
					(size 1.27 1.27)
				)
			)
		)
		(duplicate_pad_numbers_are_jumpers no)
		(pad "" thru_hole circle
			(at 2.29997 -5.649976 90)
			(size 2.8194 2.8194)
			(drill 2.4384)
			(layers "*.Cu" "*.Mask")
			(remove_unused_layers no)
			(clearance 0.127)
			(thermal_gap 0.127)
		)
		(pad "" thru_hole oval
			(at 2.29997 68.90004 90)
			(size 2.8194 1.5748)
			(drill oval 2.4384 1.1938)
			(layers "*.Cu" "*.Mask")
			(remove_unused_layers no)
			(clearance 0.127)
			(thermal_gap 0.127)
		)
		(pad "" thru_hole circle
			(at 2.29997 132.299964 90)
			(size 2.8194 2.8194)
			(drill 2.4384)
			(layers "*.Cu" "*.Mask")
			(remove_unused_layers no)
			(clearance 0.127)
			(thermal_gap 0.127)
		)
		(pad "1" smd rect
			(at 0 0 90)
			(size 1.8034 0.508)
			(layers "F.Cu" "F.Mask" "F.Paste")
			(net "P12V_NVDIMM_DEF")
		)
		(pad "2" smd rect
			(at 0 0.849884 90)
			(size 1.8034 0.508)
			(layers "F.Cu" "F.Mask" "F.Paste")
			(net "GND")
		)
		(pad "3" smd rect
			(at 0 1.700022 90)
			(size 1.8034 0.508)
			(layers "F.Cu" "F.Mask" "F.Paste")
			(net "M_F_DQ<5>")
		)
		(pad "4" smd rect
			(at 0 2.549906 90)
			(size 1.8034 0.508)
			(layers "F.Cu" "F.Mask" "F.Paste")
			(net "GND")
		)
		(pad "5" smd rect
			(at 0 3.400044 90)
			(size 1.8034 0.508)
			(layers "F.Cu" "F.Mask" "F.Paste")
			(net "M_F_DQ<1>")
		)
		(pad "6" smd rect
			(at 0 4.249928 90)
			(size 1.8034 0.508)
			(layers "F.Cu" "F.Mask" "F.Paste")
			(net "GND")
		)
		(pad "7" smd rect
			(at 0 5.100066 90)
			(size 1.8034 0.508)
			(layers "F.Cu" "F.Mask" "F.Paste")
			(net "M_F_DQS_DP<9>")
		)
		(pad "8" smd rect
			(at 0 5.94995 90)
			(size 1.8034 0.508)
			(layers "F.Cu" "F.Mask" "F.Paste")
			(net "M_F_DQS_DN<9>")
		)
		(pad "9" smd rect
			(at 0 6.800088 90)
			(size 1.8034 0.508)
			(layers "F.Cu" "F.Mask" "F.Paste")
			(net "GND")
		)
		(pad "10" smd rect
			(at 0 7.649972 90)
			(size 1.8034 0.508)
			(layers "F.Cu" "F.Mask" "F.Paste")
			(net "M_F_DQ<7>")
		)
		(pad "11" smd rect
			(at 0 8.50011 90)
			(size 1.8034 0.508)
			(layers "F.Cu" "F.Mask" "F.Paste")
			(net "GND")
		)
		(pad "12" smd rect
			(at 0 9.349994 90)
			(size 1.8034 0.508)
			(layers "F.Cu" "F.Mask" "F.Paste")
			(net "M_F_DQ<3>")
		)
		(pad "13" smd rect
			(at 0 10.199878 90)
			(size 1.8034 0.508)
			(layers "F.Cu" "F.Mask" "F.Paste")
			(net "GND")
		)
		(pad "14" smd rect
			(at 0 11.050016 90)
			(size 1.8034 0.508)
			(layers "F.Cu" "F.Mask" "F.Paste")
			(net "M_F_DQ<13>")
		)
		(pad "15" smd rect
			(at 0 11.8999 90)
			(size 1.8034 0.508)
			(layers "F.Cu" "F.Mask" "F.Paste")
			(net "GND")
		)
		(pad "16" smd rect
			(at 0 12.750038 90)
			(size 1.8034 0.508)
			(layers "F.Cu" "F.Mask" "F.Paste")
			(net "M_F_DQ<9>")
		)
		(pad "17" smd rect
			(at 0 13.599922 90)
			(size 1.8034 0.508)
			(layers "F.Cu" "F.Mask" "F.Paste")
			(net "GND")
		)
		(pad "18" smd rect
			(at 0 14.45006 90)
			(size 1.8034 0.508)
			(layers "F.Cu" "F.Mask" "F.Paste")
			(net "M_F_DQS_DP<10>")
		)
		(pad "19" smd rect
			(at 0 15.299944 90)
			(size 1.8034 0.508)
			(layers "F.Cu" "F.Mask" "F.Paste")
			(net "M_F_DQS_DN<10>")
		)
		(pad "20" smd rect
			(at 0 16.150082 90)
			(size 1.8034 0.508)
			(layers "F.Cu" "F.Mask" "F.Paste")
			(net "GND")
		)
		(pad "21" smd rect
			(at 0 16.999966 90)
			(size 1.8034 0.508)
			(layers "F.Cu" "F.Mask" "F.Paste")
			(net "M_F_DQ<15>")
		)
		(pad "22" smd rect
			(at 0 17.850104 90)
			(size 1.8034 0.508)
			(layers "F.Cu" "F.Mask" "F.Paste")
			(net "GND")
		)
		(pad "23" smd rect
			(at 0 18.699988 90)
			(size 1.8034 0.508)
			(layers "F.Cu" "F.Mask" "F.Paste")
			(net "M_F_DQ<11>")
		)
		(pad "24" smd rect
			(at 0 19.550126 90)
			(size 1.8034 0.508)
			(layers "F.Cu" "F.Mask" "F.Paste")
			(net "GND")
		)
		(pad "25" smd rect
			(at 0 20.40001 90)
			(size 1.8034 0.508)
			(layers "F.Cu" "F.Mask" "F.Paste")
			(net "M_F_DQ<21>")
		)
		(pad "26" smd rect
			(at 0 21.249894 90)
			(size 1.8034 0.508)
			(layers "F.Cu" "F.Mask" "F.Paste")
			(net "GND")
		)
		(pad "27" smd rect
			(at 0 22.100032 90)
			(size 1.8034 0.508)
			(layers "F.Cu" "F.Mask" "F.Paste")
			(net "M_F_DQ<17>")
		)
		(pad "28" smd rect
			(at 0 22.949916 90)
			(size 1.8034 0.508)
			(layers "F.Cu" "F.Mask" "F.Paste")
			(net "GND")
		)
		(pad "29" smd rect
			(at 0 23.800054 90)
			(size 1.8034 0.508)
			(layers "F.Cu" "F.Mask" "F.Paste")
			(net "M_F_DQS_DP<11>")
		)
		(pad "30" smd rect
			(at 0 24.649938 90)
			(size 1.8034 0.508)
			(layers "F.Cu" "F.Mask" "F.Paste")
			(net "M_F_DQS_DN<11>")
		)
		(pad "31" smd rect
			(at 0 25.500076 90)
			(size 1.8034 0.508)
			(layers "F.Cu" "F.Mask" "F.Paste")
			(net "GND")
		)
		(pad "32" smd rect
			(at 0 26.34996 90)
			(size 1.8034 0.508)
			(layers "F.Cu" "F.Mask" "F.Paste")
			(net "M_F_DQ<23>")
		)
		(pad "33" smd rect
			(at 0 27.200098 90)
			(size 1.8034 0.508)
			(layers "F.Cu" "F.Mask" "F.Paste")
			(net "GND")
		)
		(pad "34" smd rect
			(at 0 28.049982 90)
			(size 1.8034 0.508)
			(layers "F.Cu" "F.Mask" "F.Paste")
			(net "M_F_DQ<19>")
		)
		(pad "35" smd rect
			(at 0 28.90012 90)
			(size 1.8034 0.508)
			(layers "F.Cu" "F.Mask" "F.Paste")
			(net "GND")
		)
		(pad "36" smd rect
			(at 0 29.750004 90)
			(size 1.8034 0.508)
			(layers "F.Cu" "F.Mask" "F.Paste")
			(net "M_F_DQ<29>")
		)
		(pad "37" smd rect
			(at 0 30.599888 90)
			(size 1.8034 0.508)
			(layers "F.Cu" "F.Mask" "F.Paste")
			(net "GND")
		)
		(pad "38" smd rect
			(at 0 31.450026 90)
			(size 1.8034 0.508)
			(layers "F.Cu" "F.Mask" "F.Paste")
			(net "M_F_DQ<25>")
		)
		(pad "39" smd rect
			(at 0 32.29991 90)
			(size 1.8034 0.508)
			(layers "F.Cu" "F.Mask" "F.Paste")
			(net "GND")
		)
		(pad "40" smd rect
			(at 0 33.150048 90)
			(size 1.8034 0.508)
			(layers "F.Cu" "F.Mask" "F.Paste")
			(net "M_F_DQS_DP<12>")
		)
		(pad "41" smd rect
			(at 0 33.999932 90)
			(size 1.8034 0.508)
			(layers "F.Cu" "F.Mask" "F.Paste")
			(net "M_F_DQS_DN<12>")
		)
		(pad "42" smd rect
			(at 0 34.85007 90)
			(size 1.8034 0.508)
			(layers "F.Cu" "F.Mask" "F.Paste")
			(net "GND")
		)
		(pad "43" smd rect
			(at 0 35.699954 90)
			(size 1.8034 0.508)
			(layers "F.Cu" "F.Mask" "F.Paste")
			(net "M_F_DQ<31>")
		)
		(pad "44" smd rect
			(at 0 36.550092 90)
			(size 1.8034 0.508)
			(layers "F.Cu" "F.Mask" "F.Paste")
			(net "GND")
		)
		(pad "45" smd rect
			(at 0 37.399976 90)
			(size 1.8034 0.508)
			(layers "F.Cu" "F.Mask" "F.Paste")
			(net "M_F_DQ<27>")
		)
		(pad "46" smd rect
			(at 0 38.250114 90)
			(size 1.8034 0.508)
			(layers "F.Cu" "F.Mask" "F.Paste")
			(net "GND")
		)
		(pad "47" smd rect
			(at 0 39.099998 90)
			(size 1.8034 0.508)
			(layers "F.Cu" "F.Mask" "F.Paste")
			(net "M_F_ECC<5>")
		)
		(pad "48" smd rect
			(at 0 39.949882 90)
			(size 1.8034 0.508)
			(layers "F.Cu" "F.Mask" "F.Paste")
			(net "GND")
		)
	)
)
